# T6G (Grand Teton) — schematic netlist excerpt (pin names and nets, part order shuffled) for the footprints in the layout excerpt that follows; sources: Cadence DE-HDL packaged netlist, KiCad conversion of 04192023_DAF0TMB3IC0_F0TG_MB_C_brd_V02_OCP.brd

PC394_2  Q_CAP  22UF 4V 20% X6S  pkg C0805  page 218 : A = PVDDCR_CPU1_P1 ; B = GND
R1585  Q_RES  49.9 1% CHIP  pkg 0402LF  page 103 : A = I3C_SPD_DDRAF_CPU1_SCL ; B = I3C_SPD_DDRF_CPU1_SCL
R8182  Q_RES  49.9 1% CHIP  pkg 0402LF  page 210 : A = PVDDCR_CPU0_P1_RESET_N ; B = PVDDCR_CPU0_P1_RESET_N_R

(kicad_pcb
	(version 20260206)
	(generator "pcbnew")
	(generator_version "10.0")
	(general
		(thickness 1.6)
		(legacy_teardrops no)
	)
	(paper "A4")
	(title_block
		(title "04192023_DAF0TMB3IC0_F0TG_MB_C_brd_V02_OCP.brd")
		(comment 1 "Grand Teton / footprints 6451-6453 of 8354")
	)
	(layers
		(0 "F.Cu" signal "TOP")
		(4 "In1.Cu" signal "GND")
		(6 "In2.Cu" signal "IN1")
		(8 "In3.Cu" signal "GND1")
		(10 "In4.Cu" signal "IN2")
		(12 "In5.Cu" signal "GND2")
		(14 "In6.Cu" signal "IN3")
		(16 "In7.Cu" signal "GND3")
		(18 "In8.Cu" signal "VCC")
		(20 "In9.Cu" signal "VCC1")
		(22 "In10.Cu" signal "GND4")
		(24 "In11.Cu" signal "IN4")
		(26 "In12.Cu" signal "GND5")
		(28 "In13.Cu" signal "IN5")
		(30 "In14.Cu" signal "GND6")
		(32 "In15.Cu" signal "IN6")
		(34 "In16.Cu" signal "GND7")
		(2 "B.Cu" signal "BOTTOM")
		(9 "F.Adhes" user "F.Adhesive")
		(11 "B.Adhes" user "B.Adhesive")
		(13 "F.Paste" user "Package Geometry/Pastemask Top")
		(15 "B.Paste" user "Package Geometry/Pastemask Bottom")
		(5 "F.SilkS" user "Ref Des/Silkscreen Top")
		(7 "B.SilkS" user "Ref Des/Silkscreen Bottom")
		(1 "F.Mask" user "Board Geometry/Soldermask Top")
		(3 "B.Mask" user "Board Geometry/Soldermask Bottom")
		(17 "Dwgs.User" user "User.Drawings")
		(19 "Cmts.User" user "User.Comments")
		(21 "Eco1.User" user "User.Eco1")
		(23 "Eco2.User" user "User.Eco2")
		(25 "Edge.Cuts" user "Board Geometry/Outline")
		(27 "Margin" user)
		(31 "F.CrtYd" user "Package Geometry/Place Bound Top")
		(29 "B.CrtYd" user "Package Geometry/Place Bound Bottom")
		(35 "F.Fab" user "Ref Des/Assembly Top")
		(33 "B.Fab" user "Ref Des/Assembly Bottom")
	)
	(footprint ""
		(layer "B.Cu")
		(at 90.209878 -143.86941 180)
		(property "Reference" "R8182"
			(at 0 0 0)
			(layer "B.SilkS")
			(hide yes)
			(effects
				(font
					(size 1.27 1.27)
				)
				(justify mirror)
			)
		)
		(property "Value" ""
			(at 0 0 0)
			(layer "B.Fab")
			(effects
				(font
					(size 1.27 1.27)
				)
				(justify mirror)
			)
		)
		(duplicate_pad_numbers_are_jumpers no)
		(fp_line
			(start 0.7874 0.4064)
			(end 0.7874 -0.4064)
			(stroke
				(width 0.1524)
				(type default)
			)
			(layer "B.SilkS")
		)
		(fp_line
			(start 0.7874 -0.4064)
			(end -0.7874 -0.4064)
			(stroke
				(width 0.1524)
				(type default)
			)
			(layer "B.SilkS")
		)
		(fp_line
			(start -0.7874 0.4064)
			(end 0.7874 0.4064)
			(stroke
				(width 0.1524)
				(type default)
			)
			(layer "B.SilkS")
		)
		(fp_line
			(start -0.7874 -0.4064)
			(end -0.7874 0.4064)
			(stroke
				(width 0.1524)
				(type default)
			)
			(layer "B.SilkS")
		)
		(fp_line
			(start 0.67945 0.3048)
			(end 0.67945 -0.305054)
			(stroke
				(width 0.1)
				(type default)
			)
			(layer "B.Fab")
		)
		(fp_line
			(start 0.67945 -0.305054)
			(end 0.12065 -0.305054)
			(stroke
				(width 0.1)
				(type default)
			)
			(layer "B.Fab")
		)
		(fp_line
			(start 0.12065 0.3048)
			(end 0.67945 0.3048)
			(stroke
				(width 0.1)
				(type default)
			)
			(layer "B.Fab")
		)
		(fp_line
			(start 0.12065 0.2794)
			(end 0.12065 0.3048)
			(stroke
				(width 0.1)
				(type default)
			)
			(layer "B.Fab")
		)
		(fp_line
			(start 0.12065 -0.2794)
			(end -0.12065 -0.2794)
			(stroke
				(width 0.1)
				(type default)
			)
			(layer "B.Fab")
		)
		(fp_line
			(start 0.12065 -0.305054)
			(end 0.12065 -0.2794)
			(stroke
				(width 0.1)
				(type default)
			)
			(layer "B.Fab")
		)
		(fp_line
			(start -0.120396 0.3048)
			(end -0.120396 0.2794)
			(stroke
				(width 0.1)
				(type default)
			)
			(layer "B.Fab")
		)
		(fp_line
			(start -0.120396 0.2794)
			(end 0.12065 0.2794)
			(stroke
				(width 0.1)
				(type default)
			)
			(layer "B.Fab")
		)
		(fp_line
			(start -0.12065 -0.2794)
			(end -0.12065 -0.3048)
			(stroke
				(width 0.1)
				(type default)
			)
			(layer "B.Fab")
		)
		(fp_line
			(start -0.12065 -0.3048)
			(end -0.67945 -0.3048)
			(stroke
				(width 0.1)
				(type default)
			)
			(layer "B.Fab")
		)
		(fp_line
			(start -0.67945 0.3048)
			(end -0.120396 0.3048)
			(stroke
				(width 0.1)
				(type default)
			)
			(layer "B.Fab")
		)
		(fp_line
			(start -0.67945 -0.3048)
			(end -0.67945 0.3048)
			(stroke
				(width 0.1)
				(type default)
			)
			(layer "B.Fab")
		)
		(pad "1" smd circle
			(at 0.40005 0)
			(size 0 0)
			(layers "B.Cu" "B.Mask" "B.Paste")
			(net "PVDDCR_CPU0_P1_RESET_N")
		)
		(pad "2" smd circle
			(at -0.40005 0)
			(size 0 0)
			(layers "B.Cu" "B.Mask" "B.Paste")
			(net "PVDDCR_CPU0_P1_RESET_N_R")
		)
	)
	(footprint ""
		(layer "B.Cu")
		(at 90.249756 -326.346058 -90)
		(property "Reference" "PC394_2"
			(at 0 0 90)
			(layer "B.SilkS")
			(hide yes)
			(effects
				(font
					(size 1.27 1.27)
				)
				(justify mirror)
			)
		)
		(property "Value" ""
			(at 0 0 90)
			(layer "B.Fab")
			(effects
				(font
					(size 1.27 1.27)
				)
				(justify mirror)
			)
		)
		(duplicate_pad_numbers_are_jumpers no)
		(fp_line
			(start -1.524 0.762)
			(end 1.524 0.762)
			(stroke
				(width 0.1524)
				(type default)
			)
			(layer "B.SilkS")
		)
		(fp_line
			(start 1.524 0.762)
			(end 1.524 -0.762)
			(stroke
				(width 0.1524)
				(type default)
			)
			(layer "B.SilkS")
		)
		(fp_line
			(start -1.524 -0.762)
			(end -1.524 0.762)
			(stroke
				(width 0.1524)
				(type default)
			)
			(layer "B.SilkS")
		)
		(fp_line
			(start 1.524 -0.762)
			(end -1.524 -0.762)
			(stroke
				(width 0.1524)
				(type default)
			)
			(layer "B.SilkS")
		)
		(fp_line
			(start -1.1049 0.724916)
			(end -1.1049 -0.724916)
			(stroke
				(width 0.1)
				(type default)
			)
			(layer "B.Fab")
		)
		(fp_line
			(start 1.1049 0.724916)
			(end -1.1049 0.724916)
			(stroke
				(width 0.1)
				(type default)
			)
			(layer "B.Fab")
		)
		(fp_line
			(start -1.1049 -0.724916)
			(end 1.1049 -0.724916)
			(stroke
				(width 0.1)
				(type default)
			)
			(layer "B.Fab")
		)
		(fp_line
			(start 1.1049 -0.724916)
			(end 1.1049 0.724916)
			(stroke
				(width 0.1)
				(type default)
			)
			(layer "B.Fab")
		)
		(pad "1" smd rect
			(at 0.889 0 270)
			(size 1.016 1.27)
			(layers "B.Cu" "B.Mask" "B.Paste")
			(net "PVDDCR_CPU1_P1")
		)
		(pad "2" smd rect
			(at -0.889 0 270)
			(size 1.016 1.27)
			(layers "B.Cu" "B.Mask" "B.Paste")
			(net "GND")
		)
	)
	(footprint ""
		(layer "B.Cu")
		(at 20.919186 -195.012564 180)
		(property "Reference" "R1585"
			(at 0 0 0)
			(layer "B.SilkS")
			(hide yes)
			(effects
				(font
					(size 1.27 1.27)
				)
				(justify mirror)
			)
		)
		(property "Value" ""
			(at 0 0 0)
			(layer "B.Fab")
			(effects
				(font
					(size 1.27 1.27)
				)
				(justify mirror)
			)
		)
		(duplicate_pad_numbers_are_jumpers no)
		(fp_line
			(start 0.7874 0.4064)
			(end 0.7874 -0.4064)
			(stroke
				(width 0.1524)
				(type default)
			)
			(layer "B.SilkS")
		)
		(fp_line
			(start 0.7874 -0.4064)
			(end -0.7874 -0.4064)
			(stroke
				(width 0.1524)
				(type default)
			)
			(layer "B.SilkS")
		)
		(fp_line
			(start -0.7874 0.4064)
			(end 0.7874 0.4064)
			(stroke
				(width 0.1524)
				(type default)
			)
			(layer "B.SilkS")
		)
		(fp_line
			(start -0.7874 -0.4064)
			(end -0.7874 0.4064)
			(stroke
				(width 0.1524)
				(type default)
			)
			(layer "B.SilkS")
		)
		(fp_line
			(start 0.67945 0.3048)
			(end 0.67945 -0.305054)
			(stroke
				(width 0.1)
				(type default)
			)
			(layer "B.Fab")
		)
		(fp_line
			(start 0.67945 -0.305054)
			(end 0.12065 -0.305054)
			(stroke
				(width 0.1)
				(type default)
			)
			(layer "B.Fab")
		)
		(fp_line
			(start 0.12065 0.3048)
			(end 0.67945 0.3048)
			(stroke
				(width 0.1)
				(type default)
			)
			(layer "B.Fab")
		)
		(fp_line
			(start 0.12065 0.2794)
			(end 0.12065 0.3048)
			(stroke
				(width 0.1)
				(type default)
			)
			(layer "B.Fab")
		)
		(fp_line
			(start 0.12065 -0.2794)
			(end -0.12065 -0.2794)
			(stroke
				(width 0.1)
				(type default)
			)
			(layer "B.Fab")
		)
		(fp_line
			(start 0.12065 -0.305054)
			(end 0.12065 -0.2794)
			(stroke
				(width 0.1)
				(type default)
			)
			(layer "B.Fab")
		)
		(fp_line
			(start -0.120396 0.3048)
			(end -0.120396 0.2794)
			(stroke
				(width 0.1)
				(type default)
			)
			(layer "B.Fab")
		)
		(fp_line
			(start -0.120396 0.2794)
			(end 0.12065 0.2794)
			(stroke
				(width 0.1)
				(type default)
			)
			(layer "B.Fab")
		)
		(fp_line
			(start -0.12065 -0.2794)
			(end -0.12065 -0.3048)
			(stroke
				(width 0.1)
				(type default)
			)
			(layer "B.Fab")
		)
		(fp_line
			(start -0.12065 -0.3048)
			(end -0.67945 -0.3048)
			(stroke
				(width 0.1)
				(type default)
			)
			(layer "B.Fab")
		)
		(fp_line
			(start -0.67945 0.3048)
			(end -0.120396 0.3048)
			(stroke
				(width 0.1)
				(type default)
			)
			(layer "B.Fab")
		)
		(fp_line
			(start -0.67945 -0.3048)
			(end -0.67945 0.3048)
			(stroke
				(width 0.1)
				(type default)
			)
			(layer "B.Fab")
		)
		(pad "1" smd circle
			(at 0.40005 0)
			(size 0 0)
			(layers "B.Cu" "B.Mask" "B.Paste")
			(net "I3C_SPD_DDRAF_CPU1_SCL")
		)
		(pad "2" smd circle
			(at -0.40005 0)
			(size 0 0)
			(layers "B.Cu" "B.Mask" "B.Paste")
			(net "I3C_SPD_DDRF_CPU1_SCL")
		)
	)
)
